# BASEBOARD_FAB2 (Tioga Pass) — schematic netlist excerpt (pin names and nets, part order shuffled) for the footprints in the layout excerpt that follows; sources: Cadence DE-HDL packaged netlist, KiCad conversion of Wiwynn_Tioga_Pass_MB.brd

C3M23  CAP  10UF 4V 20% X6S  pkg 0603LF  page 127 : A = P1V05_PCH_STBY_VCCA_XTAL ; B = GND
C5G100  CAP_A  22.0UF 4V 20% X6S  pkg 0603V  page 243 : A = PVDDQ_KLM ; B = GND
R6L2  RES  1.00K 1% CHIP  pkg 0402  page 98 : A = PVDDQ_DEF ; B = M_F_VREF

(kicad_pcb
	(version 20260206)
	(generator "pcbnew")
	(generator_version "10.0")
	(general
		(thickness 1.6)
		(legacy_teardrops no)
	)
	(paper "A4")
	(title_block
		(title "Wiwynn_Tioga_Pass_MB.brd")
		(comment 1 "Tioga Pass / footprints 2822-2824 of 4770")
	)
	(layers
		(0 "F.Cu" signal "TOP")
		(4 "In1.Cu" signal "L2GND")
		(6 "In2.Cu" signal "L3")
		(8 "In3.Cu" signal "L4GND")
		(10 "In4.Cu" signal "L5")
		(12 "In5.Cu" signal "L6GND")
		(14 "In6.Cu" signal "L7VCC")
		(16 "In7.Cu" signal "L8VCC")
		(18 "In8.Cu" signal "L9GND")
		(20 "In9.Cu" signal "L10")
		(22 "In10.Cu" signal "L11GND")
		(24 "In11.Cu" signal "L12")
		(26 "In12.Cu" signal "L13GND")
		(2 "B.Cu" signal "BOTTOM")
		(9 "F.Adhes" user "F.Adhesive")
		(11 "B.Adhes" user "B.Adhesive")
		(13 "F.Paste" user "Package Geometry/Pastemask Top")
		(15 "B.Paste" user "Package Geometry/Pastemask Bottom")
		(5 "F.SilkS" user "Ref Des/Silkscreen Top")
		(7 "B.SilkS" user "Ref Des/Silkscreen Bottom")
		(1 "F.Mask" user "Board Geometry/Soldermask Top")
		(3 "B.Mask" user "Board Geometry/Soldermask Bottom")
		(17 "Dwgs.User" user "User.Drawings")
		(19 "Cmts.User" user "User.Comments")
		(21 "Eco1.User" user "User.Eco1")
		(23 "Eco2.User" user "User.Eco2")
		(25 "Edge.Cuts" user "Board Geometry/Outline")
		(27 "Margin" user)
		(31 "F.CrtYd" user "Package Geometry/Place Bound Top")
		(29 "B.CrtYd" user "Package Geometry/Place Bound Bottom")
		(35 "F.Fab" user "Ref Des/Assembly Top")
		(33 "B.Fab" user "Ref Des/Assembly Bottom")
	)
	(footprint ""
		(layer "B.Cu")
		(at 193.675 -154.559 180)
		(property "Reference" "R6L2"
			(at 0 0 0)
			(layer "B.SilkS")
			(hide yes)
			(effects
				(font
					(size 1.27 1.27)
				)
				(justify mirror)
			)
		)
		(property "Value" ""
			(at 0 0 0)
			(layer "B.Fab")
			(effects
				(font
					(size 1.27 1.27)
				)
				(justify mirror)
			)
		)
		(duplicate_pad_numbers_are_jumpers no)
		(fp_poly
			(pts
				(xy 0.2794 -0.1016) (xy -0.2794 -0.1016) (xy -0.2794 0.9906) (xy 0.2794 0.9906)
			)
			(stroke
				(width 0)
				(type default)
			)
			(fill no)
			(layer "B.CrtYd")
		)
		(fp_line
			(start 0.2794 0.9906)
			(end -0.2794 0.9906)
			(stroke
				(width 0.1)
				(type default)
			)
			(layer "B.Fab")
		)
		(fp_line
			(start 0.2794 -0.1016)
			(end 0.2794 0.9906)
			(stroke
				(width 0.1)
				(type default)
			)
			(layer "B.Fab")
		)
		(fp_line
			(start -0.2794 0.9906)
			(end -0.2794 -0.1016)
			(stroke
				(width 0.1)
				(type default)
			)
			(layer "B.Fab")
		)
		(fp_line
			(start -0.2794 -0.1016)
			(end 0.2794 -0.1016)
			(stroke
				(width 0.1)
				(type default)
			)
			(layer "B.Fab")
		)
		(pad "1" smd rect
			(at 0 0)
			(size 0.508 0.508)
			(layers "B.Cu" "B.Mask" "B.Paste")
			(net "PVDDQ_DEF")
		)
		(pad "2" smd rect
			(at 0 0.889)
			(size 0.508 0.508)
			(layers "B.Cu" "B.Mask" "B.Paste")
			(net "M_F_VREF")
		)
		(zone
			(layer "B.Cu")
			(hatch none 0.5)
			(connect_pads
				(clearance 0)
			)
			(min_thickness 0.25)
			(keepout
				(tracks not_allowed)
				(vias allowed)
				(pads allowed)
				(copperpour not_allowed)
				(footprints allowed)
			)
			(placement
				(enabled no)
				(sheetname "")
			)
			(fill
				(thermal_gap 0.5)
				(thermal_bridge_width 0.5)
				(island_removal_mode 0)
			)
			(polygon
				(pts
					(xy 193.421 -155.194) (xy 193.929 -155.194) (xy 193.929 -154.813) (xy 193.421 -154.813)
				)
			)
		)
		(zone
			(layer "B.Cu")
			(hatch none 0.5)
			(connect_pads
				(clearance 0)
			)
			(min_thickness 0.25)
			(keepout
				(tracks allowed)
				(vias not_allowed)
				(pads allowed)
				(copperpour not_allowed)
				(footprints allowed)
			)
			(placement
				(enabled no)
				(sheetname "")
			)
			(fill
				(thermal_gap 0.5)
				(thermal_bridge_width 0.5)
				(island_removal_mode 0)
			)
			(polygon
				(pts
					(xy 193.421 -154.813) (xy 193.929 -154.813) (xy 193.929 -155.194) (xy 193.421 -155.194)
				)
			)
		)
	)
	(footprint ""
		(layer "B.Cu")
		(at 378.1298 -133.9088 -90)
		(property "Reference" "C3M23"
			(at 0 0 90)
			(layer "B.SilkS")
			(hide yes)
			(effects
				(font
					(size 1.27 1.27)
				)
				(justify mirror)
			)
		)
		(property "Value" ""
			(at 0 0 90)
			(layer "B.Fab")
			(effects
				(font
					(size 1.27 1.27)
				)
				(justify mirror)
			)
		)
		(duplicate_pad_numbers_are_jumpers no)
		(fp_poly
			(pts
				(xy 0.4953 -0.2032) (xy -0.4953 -0.2032) (xy -0.4953 1.6002) (xy 0.4953 1.6002)
			)
			(stroke
				(width 0)
				(type default)
			)
			(fill no)
			(layer "B.CrtYd")
		)
		(fp_line
			(start -0.4953 1.6002)
			(end 0.4953 1.6002)
			(stroke
				(width 0.1)
				(type default)
			)
			(layer "B.Fab")
		)
		(fp_line
			(start 0.4953 1.6002)
			(end 0.4953 -0.2032)
			(stroke
				(width 0.1)
				(type default)
			)
			(layer "B.Fab")
		)
		(fp_line
			(start -0.4953 -0.2032)
			(end -0.4953 1.6002)
			(stroke
				(width 0.1)
				(type default)
			)
			(layer "B.Fab")
		)
		(fp_line
			(start 0.4953 -0.2032)
			(end -0.4953 -0.2032)
			(stroke
				(width 0.1)
				(type default)
			)
			(layer "B.Fab")
		)
		(pad "1" smd rect
			(at 0 0 90)
			(size 0.762 0.889)
			(layers "B.Cu" "B.Mask" "B.Paste")
			(net "P1V05_PCH_STBY_VCCA_XTAL")
		)
		(pad "2" smd rect
			(at 0 1.397 90)
			(size 0.762 0.889)
			(layers "B.Cu" "B.Mask" "B.Paste")
			(net "GND")
		)
		(zone
			(layer "B.Cu")
			(hatch none 0.5)
			(connect_pads
				(clearance 0)
			)
			(min_thickness 0.25)
			(keepout
				(tracks not_allowed)
				(vias allowed)
				(pads allowed)
				(copperpour not_allowed)
				(footprints allowed)
			)
			(placement
				(enabled no)
				(sheetname "")
			)
			(fill
				(thermal_gap 0.5)
				(thermal_bridge_width 0.5)
				(island_removal_mode 0)
			)
			(polygon
				(pts
					(xy 377.6853 -133.5278) (xy 377.6853 -134.2898) (xy 377.1773 -134.2898) (xy 377.1773 -133.5278)
				)
			)
		)
	)
	(footprint ""
		(layer "B.Cu")
		(at 83.856068 -149.8092 -90)
		(property "Reference" "C5G100"
			(at -1.14681 0.76708 0)
			(unlocked yes)
			(layer "B.SilkS")
			(effects
				(font
					(size 0.7874 0.5842)
					(thickness 0.1524)
				)
				(justify mirror)
			)
		)
		(property "Value" ""
			(at 0 0 90)
			(layer "B.Fab")
			(effects
				(font
					(size 1.27 1.27)
				)
				(justify mirror)
			)
		)
		(duplicate_pad_numbers_are_jumpers no)
		(fp_rect
			(start 0.4953 1.6002)
			(end -0.4953 -0.2032)
			(stroke
				(width 0)
				(type default)
			)
			(fill no)
			(layer "B.CrtYd")
		)
		(fp_line
			(start -0.4953 1.6002)
			(end 0.4953 1.6002)
			(stroke
				(width 0.1)
				(type default)
			)
			(layer "B.Fab")
		)
		(fp_line
			(start 0.4953 1.6002)
			(end 0.4953 -0.2032)
			(stroke
				(width 0.1)
				(type default)
			)
			(layer "B.Fab")
		)
		(fp_line
			(start -0.4953 -0.2032)
			(end -0.4953 1.6002)
			(stroke
				(width 0.1)
				(type default)
			)
			(layer "B.Fab")
		)
		(fp_line
			(start 0.4953 -0.2032)
			(end -0.4953 -0.2032)
			(stroke
				(width 0.1)
				(type default)
			)
			(layer "B.Fab")
		)
		(pad "1" smd rect
			(at 0 0 90)
			(size 0.762 0.889)
			(layers "B.Cu" "B.Mask" "B.Paste")
			(net "PVDDQ_KLM")
		)
		(pad "2" smd rect
			(at 0 1.397 90)
			(size 0.762 0.889)
			(layers "B.Cu" "B.Mask" "B.Paste")
			(net "GND")
		)
		(zone
			(layer "B.Cu")
			(hatch none 0.5)
			(connect_pads
				(clearance 0)
			)
			(min_thickness 0.25)
			(keepout
				(tracks not_allowed)
				(vias allowed)
				(pads allowed)
				(copperpour not_allowed)
				(footprints allowed)
			)
			(placement
				(enabled no)
				(sheetname "")
			)
			(fill
				(thermal_gap 0.5)
				(thermal_bridge_width 0.5)
				(island_removal_mode 0)
			)
			(polygon
				(pts
					(xy 82.903568 -149.4282) (xy 83.411568 -149.4282) (xy 83.411568 -150.1902) (xy 82.903568 -150.1902)
				)
			)
		)
	)
)
